(kicad_pcb
	(version 20260206)
	(generator "pcbnew")
	(generator_version "10.0")
	(general
		(thickness 1.6)
		(legacy_teardrops no)
	)
	(paper "A4")
	(title_block
		(title "03242023_DA0F0TMBIJ0_F0T_Motherboard_J_brd_V01_OCP.brd")
		(comment 1 "Grand Teton / footprints 4317-4322 of 6105")
	)
	(layers
		(0 "F.Cu" signal "TOP")
		(4 "In1.Cu" signal "GND")
		(6 "In2.Cu" signal "IN1")
		(8 "In3.Cu" signal "GND1")
		(10 "In4.Cu" signal "IN2")
		(12 "In5.Cu" signal "GND2")
		(14 "In6.Cu" signal "IN3")
		(16 "In7.Cu" signal "GND3")
		(18 "In8.Cu" signal "VCC")
		(20 "In9.Cu" signal "VCC1")
		(22 "In10.Cu" signal "GND4")
		(24 "In11.Cu" signal "IN4")
		(26 "In12.Cu" signal "GND5")
		(28 "In13.Cu" signal "IN5")
		(30 "In14.Cu" signal "GND6")
		(32 "In15.Cu" signal "IN6")
		(34 "In16.Cu" signal "GND7")
		(2 "B.Cu" signal "BOTTOM")
		(9 "F.Adhes" user "F.Adhesive")
		(11 "B.Adhes" user "B.Adhesive")
		(13 "F.Paste" user "Package Geometry/Pastemask Top")
		(15 "B.Paste" user "Package Geometry/Pastemask Bottom")
		(5 "F.SilkS" user "Ref Des/Silkscreen Top")
		(7 "B.SilkS" user "Ref Des/Silkscreen Bottom")
		(1 "F.Mask" user "Board Geometry/Soldermask Top")
		(3 "B.Mask" user "Board Geometry/Soldermask Bottom")
		(17 "Dwgs.User" user "User.Drawings")
		(19 "Cmts.User" user "User.Comments")
		(21 "Eco1.User" user "User.Eco1")
		(23 "Eco2.User" user "User.Eco2")
		(25 "Edge.Cuts" user "Board Geometry/Outline")
		(27 "Margin" user)
		(31 "F.CrtYd" user "Package Geometry/Place Bound Top")
		(29 "B.CrtYd" user "Package Geometry/Place Bound Bottom")
		(35 "F.Fab" user "Ref Des/Assembly Top")
		(33 "B.Fab" user "Ref Des/Assembly Bottom")
	)
	(footprint ""
		(layer "B.Cu")
		(at 203.33208 -35.372548 180)
		(property "Reference" "R3579"
			(at 0 0 0)
			(layer "B.SilkS")
			(hide yes)
			(effects
				(font
					(size 1.27 1.27)
				)
				(justify mirror)
			)
		)
		(property "Value" ""
			(at 0 0 0)
			(layer "B.Fab")
			(effects
				(font
					(size 1.27 1.27)
				)
				(justify mirror)
			)
		)
		(duplicate_pad_numbers_are_jumpers no)
		(fp_line
			(start 0.7874 0.4064)
			(end 0.7874 -0.4064)
			(stroke
				(width 0.1524)
				(type default)
			)
			(layer "B.SilkS")
		)
		(fp_line
			(start 0.7874 -0.4064)
			(end -0.7874 -0.4064)
			(stroke
				(width 0.1524)
				(type default)
			)
			(layer "B.SilkS")
		)
		(fp_line
			(start -0.7874 0.4064)
			(end 0.7874 0.4064)
			(stroke
				(width 0.1524)
				(type default)
			)
			(layer "B.SilkS")
		)
		(fp_line
			(start -0.7874 -0.4064)
			(end -0.7874 0.4064)
			(stroke
				(width 0.1524)
				(type default)
			)
			(layer "B.SilkS")
		)
		(fp_line
			(start 0.67945 0.3048)
			(end 0.67945 -0.305054)
			(stroke
				(width 0.1)
				(type default)
			)
			(layer "B.Fab")
		)
		(fp_line
			(start 0.67945 -0.305054)
			(end 0.12065 -0.305054)
			(stroke
				(width 0.1)
				(type default)
			)
			(layer "B.Fab")
		)
		(fp_line
			(start 0.12065 0.3048)
			(end 0.67945 0.3048)
			(stroke
				(width 0.1)
				(type default)
			)
			(layer "B.Fab")
		)
		(fp_line
			(start 0.12065 0.2794)
			(end 0.12065 0.3048)
			(stroke
				(width 0.1)
				(type default)
			)
			(layer "B.Fab")
		)
		(fp_line
			(start 0.12065 -0.2794)
			(end -0.12065 -0.2794)
			(stroke
				(width 0.1)
				(type default)
			)
			(layer "B.Fab")
		)
		(fp_line
			(start 0.12065 -0.305054)
			(end 0.12065 -0.2794)
			(stroke
				(width 0.1)
				(type default)
			)
			(layer "B.Fab")
		)
		(fp_line
			(start -0.120396 0.3048)
			(end -0.120396 0.2794)
			(stroke
				(width 0.1)
				(type default)
			)
			(layer "B.Fab")
		)
		(fp_line
			(start -0.120396 0.2794)
			(end 0.12065 0.2794)
			(stroke
				(width 0.1)
				(type default)
			)
			(layer "B.Fab")
		)
		(fp_line
			(start -0.12065 -0.2794)
			(end -0.12065 -0.3048)
			(stroke
				(width 0.1)
				(type default)
			)
			(layer "B.Fab")
		)
		(fp_line
			(start -0.12065 -0.3048)
			(end -0.67945 -0.3048)
			(stroke
				(width 0.1)
				(type default)
			)
			(layer "B.Fab")
		)
		(fp_line
			(start -0.67945 0.3048)
			(end -0.120396 0.3048)
			(stroke
				(width 0.1)
				(type default)
			)
			(layer "B.Fab")
		)
		(fp_line
			(start -0.67945 -0.3048)
			(end -0.67945 0.3048)
			(stroke
				(width 0.1)
				(type default)
			)
			(layer "B.Fab")
		)
		(pad "1" smd circle
			(at 0.40005 0)
			(size 0 0)
			(layers "B.Cu" "B.Mask" "B.Paste")
			(net "P12V_SCM")
		)
		(pad "2" smd circle
			(at -0.40005 0)
			(size 0 0)
			(layers "B.Cu" "B.Mask" "B.Paste")
			(net "VSENSE_P12V_INA230_5_INN")
		)
	)
	(footprint ""
		(layer "B.Cu")
		(at 38.328346 -319.268856 180)
		(property "Reference" "C56"
			(at 0 0 0)
			(layer "B.SilkS")
			(hide yes)
			(effects
				(font
					(size 1.27 1.27)
				)
				(justify mirror)
			)
		)
		(property "Value" ""
			(at 0 0 0)
			(layer "B.Fab")
			(effects
				(font
					(size 1.27 1.27)
				)
				(justify mirror)
			)
		)
		(duplicate_pad_numbers_are_jumpers no)
		(fp_line
			(start 0.7874 0.4064)
			(end 0.7874 -0.4064)
			(stroke
				(width 0.1524)
				(type default)
			)
			(layer "B.SilkS")
		)
		(fp_line
			(start 0.7874 -0.4064)
			(end -0.7874 -0.4064)
			(stroke
				(width 0.1524)
				(type default)
			)
			(layer "B.SilkS")
		)
		(fp_line
			(start -0.7874 0.4064)
			(end 0.7874 0.4064)
			(stroke
				(width 0.1524)
				(type default)
			)
			(layer "B.SilkS")
		)
		(fp_line
			(start -0.7874 -0.4064)
			(end -0.7874 0.4064)
			(stroke
				(width 0.1524)
				(type default)
			)
			(layer "B.SilkS")
		)
		(fp_line
			(start 0.67945 0.3048)
			(end 0.67945 -0.305054)
			(stroke
				(width 0.1)
				(type default)
			)
			(layer "B.Fab")
		)
		(fp_line
			(start 0.67945 -0.305054)
			(end 0.12065 -0.305054)
			(stroke
				(width 0.1)
				(type default)
			)
			(layer "B.Fab")
		)
		(fp_line
			(start 0.12065 0.3048)
			(end 0.67945 0.3048)
			(stroke
				(width 0.1)
				(type default)
			)
			(layer "B.Fab")
		)
		(fp_line
			(start 0.12065 0.2794)
			(end 0.12065 0.3048)
			(stroke
				(width 0.1)
				(type default)
			)
			(layer "B.Fab")
		)
		(fp_line
			(start 0.12065 -0.2794)
			(end -0.12065 -0.2794)
			(stroke
				(width 0.1)
				(type default)
			)
			(layer "B.Fab")
		)
		(fp_line
			(start 0.12065 -0.305054)
			(end 0.12065 -0.2794)
			(stroke
				(width 0.1)
				(type default)
			)
			(layer "B.Fab")
		)
		(fp_line
			(start -0.120396 0.3048)
			(end -0.120396 0.2794)
			(stroke
				(width 0.1)
				(type default)
			)
			(layer "B.Fab")
		)
		(fp_line
			(start -0.120396 0.2794)
			(end 0.12065 0.2794)
			(stroke
				(width 0.1)
				(type default)
			)
			(layer "B.Fab")
		)
		(fp_line
			(start -0.12065 -0.2794)
			(end -0.12065 -0.3048)
			(stroke
				(width 0.1)
				(type default)
			)
			(layer "B.Fab")
		)
		(fp_line
			(start -0.12065 -0.3048)
			(end -0.67945 -0.3048)
			(stroke
				(width 0.1)
				(type default)
			)
			(layer "B.Fab")
		)
		(fp_line
			(start -0.67945 0.3048)
			(end -0.120396 0.3048)
			(stroke
				(width 0.1)
				(type default)
			)
			(layer "B.Fab")
		)
		(fp_line
			(start -0.67945 -0.3048)
			(end -0.67945 0.3048)
			(stroke
				(width 0.1)
				(type default)
			)
			(layer "B.Fab")
		)
		(pad "1" smd circle
			(at 0.40005 0)
			(size 0 0)
			(layers "B.Cu" "B.Mask" "B.Paste")
			(net "P3V3_AUX")
		)
		(pad "2" smd circle
			(at -0.40005 0)
			(size 0 0)
			(layers "B.Cu" "B.Mask" "B.Paste")
			(net "GND")
		)
	)
	(footprint ""
		(layer "B.Cu")
		(at 185.368438 -315.458602 180)
		(property "Reference" "D48"
			(at 2.132838 -2.945384 0)
			(unlocked yes)
			(layer "B.SilkS")
			(effects
				(font
					(size 0.7874 0.5842)
					(thickness 0.1524)
				)
				(justify left mirror)
			)
		)
		(property "Value" ""
			(at 0 0 0)
			(layer "B.Fab")
			(effects
				(font
					(size 1.27 1.27)
				)
				(justify mirror)
			)
		)
		(duplicate_pad_numbers_are_jumpers no)
		(fp_line
			(start 2.050796 0.700024)
			(end 2.050796 -0.700024)
			(stroke
				(width 0.1524)
				(type default)
			)
			(layer "B.SilkS")
		)
		(fp_line
			(start 2.050796 -0.700024)
			(end -2.050796 -0.700024)
			(stroke
				(width 0.1524)
				(type default)
			)
			(layer "B.SilkS")
		)
		(fp_line
			(start 0.30607 0.500126)
			(end -0.193802 0)
			(stroke
				(width 0.1524)
				(type default)
			)
			(layer "B.SilkS")
		)
		(fp_line
			(start 0.30607 -0.500126)
			(end 0.30607 0.500126)
			(stroke
				(width 0.1524)
				(type default)
			)
			(layer "B.SilkS")
		)
		(fp_line
			(start -0.193802 0)
			(end 0.30607 -0.500126)
			(stroke
				(width 0.1524)
				(type default)
			)
			(layer "B.SilkS")
		)
		(fp_line
			(start -0.293878 -0.500126)
			(end -0.293878 0.500126)
			(stroke
				(width 0.1524)
				(type default)
			)
			(layer "B.SilkS")
		)
		(fp_line
			(start -2.050796 0.700024)
			(end 2.050796 0.700024)
			(stroke
				(width 0.1524)
				(type default)
			)
			(layer "B.SilkS")
		)
		(fp_line
			(start -2.050796 -0.700024)
			(end -2.050796 0.700024)
			(stroke
				(width 0.1524)
				(type default)
			)
			(layer "B.SilkS")
		)
		(fp_line
			(start -2.051304 0.6985)
			(end -2.051304 0.635)
			(stroke
				(width 0.1524)
				(type default)
			)
			(layer "B.SilkS")
		)
		(fp_line
			(start -2.051304 0.635)
			(end -2.152904 0.635)
			(stroke
				(width 0.1524)
				(type default)
			)
			(layer "B.SilkS")
		)
		(fp_line
			(start -2.064004 -0.6731)
			(end -2.064004 -0.6985)
			(stroke
				(width 0.1524)
				(type default)
			)
			(layer "B.SilkS")
		)
		(fp_line
			(start -2.064004 -0.6985)
			(end -2.229104 -0.6985)
			(stroke
				(width 0.1524)
				(type default)
			)
			(layer "B.SilkS")
		)
		(fp_line
			(start -2.152904 0.635)
			(end -2.152904 -0.6985)
			(stroke
				(width 0.1524)
				(type default)
			)
			(layer "B.SilkS")
		)
		(fp_line
			(start -2.152904 -0.6985)
			(end -2.343404 -0.6985)
			(stroke
				(width 0.1524)
				(type default)
			)
			(layer "B.SilkS")
		)
		(fp_line
			(start -2.229104 0.6985)
			(end -2.051304 0.6985)
			(stroke
				(width 0.1524)
				(type default)
			)
			(layer "B.SilkS")
		)
		(fp_line
			(start -2.229104 -0.6985)
			(end -2.229104 0.6985)
			(stroke
				(width 0.1524)
				(type default)
			)
			(layer "B.SilkS")
		)
		(fp_line
			(start -2.343404 0.6985)
			(end -2.216404 0.6985)
			(stroke
				(width 0.1524)
				(type default)
			)
			(layer "B.SilkS")
		)
		(fp_line
			(start -2.343404 -0.6985)
			(end -2.343404 0.6985)
			(stroke
				(width 0.1524)
				(type default)
			)
			(layer "B.SilkS")
		)
		(fp_line
			(start 0.899922 0.700024)
			(end 0.899922 -0.700024)
			(stroke
				(width 0.1)
				(type default)
			)
			(layer "B.Fab")
		)
		(fp_line
			(start 0.899922 -0.700024)
			(end -0.899922 -0.700024)
			(stroke
				(width 0.1)
				(type default)
			)
			(layer "B.Fab")
		)
		(fp_line
			(start -0.899922 0.700024)
			(end 0.899922 0.700024)
			(stroke
				(width 0.1)
				(type default)
			)
			(layer "B.Fab")
		)
		(fp_line
			(start -0.899922 -0.700024)
			(end -0.899922 0.700024)
			(stroke
				(width 0.1)
				(type default)
			)
			(layer "B.Fab")
		)
		(fp_text user "+"
			(at 3.123946 0.762 90)
			(unlocked yes)
			(layer "B.SilkS")
			(effects
				(font
					(size 1.905 1.4224)
					(thickness 0.1524)
				)
				(justify left mirror)
			)
		)
		(fp_text user "-"
			(at -3.869182 -0.885444 0)
			(unlocked yes)
			(layer "B.SilkS")
			(effects
				(font
					(size 1.905 1.4224)
					(thickness 0.1524)
				)
				(justify left mirror)
			)
		)
		(fp_text user "+"
			(at 3.123946 0.762 90)
			(unlocked yes)
			(layer "B.Fab")
			(effects
				(font
					(size 1.905 1.4224)
					(thickness 0.1524)
				)
				(justify left mirror)
			)
		)
		(fp_text user "-"
			(at -3.880104 0.23495 0)
			(unlocked yes)
			(layer "B.Fab")
			(effects
				(font
					(size 1.905 1.4224)
					(thickness 0.1524)
				)
				(justify left mirror)
			)
		)
		(pad "1" smd rect
			(at 1.199896 0 90)
			(size 0.6604 1.3716)
			(layers "B.Cu" "B.Mask" "B.Paste")
			(net "PWRGD_FAIL_CPU1_EF_R1")
		)
		(pad "2" smd rect
			(at -1.199896 0 270)
			(size 0.6604 1.3716)
			(layers "B.Cu" "B.Mask" "B.Paste")
			(net "P3V3_AUX")
		)
	)
	(footprint ""
		(layer "B.Cu")
		(at 371.676676 -366.755426 90)
		(property "Reference" "PC1257"
			(at 0 0 90)
			(layer "B.SilkS")
			(hide yes)
			(effects
				(font
					(size 1.27 1.27)
				)
				(justify mirror)
			)
		)
		(property "Value" ""
			(at 0 0 90)
			(layer "B.Fab")
			(effects
				(font
					(size 1.27 1.27)
				)
				(justify mirror)
			)
		)
		(duplicate_pad_numbers_are_jumpers no)
		(fp_line
			(start 1.524 -0.762)
			(end -1.524 -0.762)
			(stroke
				(width 0.1524)
				(type default)
			)
			(layer "B.SilkS")
		)
		(fp_line
			(start -1.524 -0.762)
			(end -1.524 0.762)
			(stroke
				(width 0.1524)
				(type default)
			)
			(layer "B.SilkS")
		)
		(fp_line
			(start 1.524 0.762)
			(end 1.524 -0.762)
			(stroke
				(width 0.1524)
				(type default)
			)
			(layer "B.SilkS")
		)
		(fp_line
			(start -1.524 0.762)
			(end 1.524 0.762)
			(stroke
				(width 0.1524)
				(type default)
			)
			(layer "B.SilkS")
		)
		(fp_line
			(start 1.1049 -0.724916)
			(end 1.1049 0.724916)
			(stroke
				(width 0.1)
				(type default)
			)
			(layer "B.Fab")
		)
		(fp_line
			(start -1.1049 -0.724916)
			(end 1.1049 -0.724916)
			(stroke
				(width 0.1)
				(type default)
			)
			(layer "B.Fab")
		)
		(fp_line
			(start 1.1049 0.724916)
			(end -1.1049 0.724916)
			(stroke
				(width 0.1)
				(type default)
			)
			(layer "B.Fab")
		)
		(fp_line
			(start -1.1049 0.724916)
			(end -1.1049 -0.724916)
			(stroke
				(width 0.1)
				(type default)
			)
			(layer "B.Fab")
		)
		(pad "1" smd rect
			(at 0.889 0 90)
			(size 1.016 1.27)
			(layers "B.Cu" "B.Mask" "B.Paste")
			(net "PVPP_HBM_CPU0")
		)
		(pad "2" smd rect
			(at -0.889 0 90)
			(size 1.016 1.27)
			(layers "B.Cu" "B.Mask" "B.Paste")
			(net "GND")
		)
	)
	(footprint ""
		(layer "B.Cu")
		(at 191.04864 -319.217548)
		(property "Reference" "R74"
			(at 0 0 0)
			(layer "B.SilkS")
			(hide yes)
			(effects
				(font
					(size 1.27 1.27)
				)
				(justify mirror)
			)
		)
		(property "Value" ""
			(at 0 0 0)
			(layer "B.Fab")
			(effects
				(font
					(size 1.27 1.27)
				)
				(justify mirror)
			)
		)
		(duplicate_pad_numbers_are_jumpers no)
		(fp_line
			(start -0.7874 -0.4064)
			(end -0.7874 0.4064)
			(stroke
				(width 0.1524)
				(type default)
			)
			(layer "B.SilkS")
		)
		(fp_line
			(start -0.7874 0.4064)
			(end 0.7874 0.4064)
			(stroke
				(width 0.1524)
				(type default)
			)
			(layer "B.SilkS")
		)
		(fp_line
			(start 0.7874 -0.4064)
			(end -0.7874 -0.4064)
			(stroke
				(width 0.1524)
				(type default)
			)
			(layer "B.SilkS")
		)
		(fp_line
			(start 0.7874 0.4064)
			(end 0.7874 -0.4064)
			(stroke
				(width 0.1524)
				(type default)
			)
			(layer "B.SilkS")
		)
		(fp_line
			(start -0.67945 -0.3048)
			(end -0.67945 0.3048)
			(stroke
				(width 0.1)
				(type default)
			)
			(layer "B.Fab")
		)
		(fp_line
			(start -0.67945 0.3048)
			(end -0.120396 0.3048)
			(stroke
				(width 0.1)
				(type default)
			)
			(layer "B.Fab")
		)
		(fp_line
			(start -0.12065 -0.3048)
			(end -0.67945 -0.3048)
			(stroke
				(width 0.1)
				(type default)
			)
			(layer "B.Fab")
		)
		(fp_line
			(start -0.12065 -0.2794)
			(end -0.12065 -0.3048)
			(stroke
				(width 0.1)
				(type default)
			)
			(layer "B.Fab")
		)
		(fp_line
			(start -0.120396 0.2794)
			(end 0.12065 0.2794)
			(stroke
				(width 0.1)
				(type default)
			)
			(layer "B.Fab")
		)
		(fp_line
			(start -0.120396 0.3048)
			(end -0.120396 0.2794)
			(stroke
				(width 0.1)
				(type default)
			)
			(layer "B.Fab")
		)
		(fp_line
			(start 0.12065 -0.305054)
			(end 0.12065 -0.2794)
			(stroke
				(width 0.1)
				(type default)
			)
			(layer "B.Fab")
		)
		(fp_line
			(start 0.12065 -0.2794)
			(end -0.12065 -0.2794)
			(stroke
				(width 0.1)
				(type default)
			)
			(layer "B.Fab")
		)
		(fp_line
			(start 0.12065 0.2794)
			(end 0.12065 0.3048)
			(stroke
				(width 0.1)
				(type default)
			)
			(layer "B.Fab")
		)
		(fp_line
			(start 0.12065 0.3048)
			(end 0.67945 0.3048)
			(stroke
				(width 0.1)
				(type default)
			)
			(layer "B.Fab")
		)
		(fp_line
			(start 0.67945 -0.305054)
			(end 0.12065 -0.305054)
			(stroke
				(width 0.1)
				(type default)
			)
			(layer "B.Fab")
		)
		(fp_line
			(start 0.67945 0.3048)
			(end 0.67945 -0.305054)
			(stroke
				(width 0.1)
				(type default)
			)
			(layer "B.Fab")
		)
		(pad "1" smd circle
			(at 0.40005 0 180)
			(size 0 0)
			(layers "B.Cu" "B.Mask" "B.Paste")
			(net "PD_CHG_CPU1_DIMM2_SAA")
		)
		(pad "2" smd circle
			(at -0.40005 0 180)
			(size 0 0)
			(layers "B.Cu" "B.Mask" "B.Paste")
			(net "GND")
		)
	)
	(footprint ""
		(layer "B.Cu")
		(at 362.736638 -182.33771 180)
		(property "Reference" "R1000"
			(at 0 0 0)
			(layer "B.SilkS")
			(hide yes)
			(effects
				(font
					(size 1.27 1.27)
				)
				(justify mirror)
			)
		)
		(property "Value" ""
			(at 0 0 0)
			(layer "B.Fab")
			(effects
				(font
					(size 1.27 1.27)
				)
				(justify mirror)
			)
		)
		(duplicate_pad_numbers_are_jumpers no)
		(fp_line
			(start 0.7874 0.4064)
			(end 0.7874 -0.4064)
			(stroke
				(width 0.1524)
				(type default)
			)
			(layer "B.SilkS")
		)
		(fp_line
			(start 0.7874 -0.4064)
			(end -0.7874 -0.4064)
			(stroke
				(width 0.1524)
				(type default)
			)
			(layer "B.SilkS")
		)
		(fp_line
			(start -0.7874 0.4064)
			(end 0.7874 0.4064)
			(stroke
				(width 0.1524)
				(type default)
			)
			(layer "B.SilkS")
		)
		(fp_line
			(start -0.7874 -0.4064)
			(end -0.7874 0.4064)
			(stroke
				(width 0.1524)
				(type default)
			)
			(layer "B.SilkS")
		)
		(fp_line
			(start 0.67945 0.3048)
			(end 0.67945 -0.305054)
			(stroke
				(width 0.1)
				(type default)
			)
			(layer "B.Fab")
		)
		(fp_line
			(start 0.67945 -0.305054)
			(end 0.12065 -0.305054)
			(stroke
				(width 0.1)
				(type default)
			)
			(layer "B.Fab")
		)
		(fp_line
			(start 0.12065 0.3048)
			(end 0.67945 0.3048)
			(stroke
				(width 0.1)
				(type default)
			)
			(layer "B.Fab")
		)
		(fp_line
			(start 0.12065 0.2794)
			(end 0.12065 0.3048)
			(stroke
				(width 0.1)
				(type default)
			)
			(layer "B.Fab")
		)
		(fp_line
			(start 0.12065 -0.2794)
			(end -0.12065 -0.2794)
			(stroke
				(width 0.1)
				(type default)
			)
			(layer "B.Fab")
		)
		(fp_line
			(start 0.12065 -0.305054)
			(end 0.12065 -0.2794)
			(stroke
				(width 0.1)
				(type default)
			)
			(layer "B.Fab")
		)
		(fp_line
			(start -0.120396 0.3048)
			(end -0.120396 0.2794)
			(stroke
				(width 0.1)
				(type default)
			)
			(layer "B.Fab")
		)
		(fp_line
			(start -0.120396 0.2794)
			(end 0.12065 0.2794)
			(stroke
				(width 0.1)
				(type default)
			)
			(layer "B.Fab")
		)
		(fp_line
			(start -0.12065 -0.2794)
			(end -0.12065 -0.3048)
			(stroke
				(width 0.1)
				(type default)
			)
			(layer "B.Fab")
		)
		(fp_line
			(start -0.12065 -0.3048)
			(end -0.67945 -0.3048)
			(stroke
				(width 0.1)
				(type default)
			)
			(layer "B.Fab")
		)
		(fp_line
			(start -0.67945 0.3048)
			(end -0.120396 0.3048)
			(stroke
				(width 0.1)
				(type default)
			)
			(layer "B.Fab")
		)
		(fp_line
			(start -0.67945 -0.3048)
			(end -0.67945 0.3048)
			(stroke
				(width 0.1)
				(type default)
			)
			(layer "B.Fab")
		)
		(pad "1" smd circle
			(at 0.40005 0)
			(size 0 0)
			(layers "B.Cu" "B.Mask" "B.Paste")
			(net "P3V3")
		)
		(pad "2" smd circle
			(at -0.40005 0)
			(size 0 0)
			(layers "B.Cu" "B.Mask" "B.Paste")
			(net "FM_SMB_PEHPCPU0_PCIE_ALERT_R_N")
		)
	)
)
